(kicad_pcb
	(version 20260206)
	(generator "pcbnew")
	(generator_version "10.0")
	(general
		(thickness 1.6)
		(legacy_teardrops no)
	)
	(paper "A4")
	(title_block
		(title "baseboard — 13948-1b.1110WZS1818.brd")
		(comment 1 "Honey Badger (Wiwynn) / footprints 1050-1057 of 2523")
	)
	(layers
		(0 "F.Cu" signal "TOP")
		(4 "In1.Cu" signal "L2GND")
		(6 "In2.Cu" signal "L3")
		(8 "In3.Cu" signal "L4VCC")
		(10 "In4.Cu" signal "L5VCC")
		(12 "In5.Cu" signal "L6")
		(14 "In6.Cu" signal "L7GND")
		(2 "B.Cu" signal "BOTTOM")
		(9 "F.Adhes" user "F.Adhesive")
		(11 "B.Adhes" user "B.Adhesive")
		(13 "F.Paste" user "Package Geometry/Pastemask Top")
		(15 "B.Paste" user "Package Geometry/Pastemask Bottom")
		(5 "F.SilkS" user "Ref Des/Silkscreen Top")
		(7 "B.SilkS" user "Ref Des/Silkscreen Bottom")
		(1 "F.Mask" user "Board Geometry/Soldermask Top")
		(3 "B.Mask" user "Board Geometry/Soldermask Bottom")
		(17 "Dwgs.User" user "User.Drawings")
		(19 "Cmts.User" user "User.Comments")
		(21 "Eco1.User" user "User.Eco1")
		(23 "Eco2.User" user "User.Eco2")
		(25 "Edge.Cuts" user "Board Geometry/Outline")
		(27 "Margin" user)
		(31 "F.CrtYd" user "Package Geometry/Place Bound Top")
		(29 "B.CrtYd" user "Package Geometry/Place Bound Bottom")
		(35 "F.Fab" user "Ref Des/Assembly Top")
		(33 "B.Fab" user "Ref Des/Assembly Bottom")
	)
	(footprint ""
		(layer "F.Cu")
		(at 300.482 -62.992 -90)
		(property "Reference" "R218"
			(at 0 0 270)
			(layer "F.SilkS")
			(hide yes)
			(effects
				(font
					(size 1.27 1.27)
				)
			)
		)
		(property "Value" "0R2J-2-GP"
			(at 0.064008 -3.993896 270)
			(unlocked yes)
			(layer "F.Fab")
			(hide yes)
			(effects
				(font
					(size 1.016 1.016)
					(thickness 0.1524)
				)
			)
		)
		(property "Device Type" "R402H16"
			(at 0.064008 -5.517896 270)
			(unlocked yes)
			(layer "F.Fab")
			(hide yes)
			(effects
				(font
					(size 1.016 1.016)
					(thickness 0.1524)
				)
			)
		)
		(duplicate_pad_numbers_are_jumpers no)
		(fp_line
			(start -0.508 -0.9398)
			(end -0.508 0.9398)
			(stroke
				(width 0.1524)
				(type default)
			)
			(layer "F.SilkS")
		)
		(fp_line
			(start 0.508 -0.9398)
			(end -0.508 -0.9398)
			(stroke
				(width 0.1524)
				(type default)
			)
			(layer "F.SilkS")
		)
		(fp_rect
			(start -0.508 0.9398)
			(end 0.508 -0.9398)
			(stroke
				(width 0)
				(type default)
			)
			(fill no)
			(layer "F.CrtYd")
		)
		(fp_rect
			(start -0.508 0.9398)
			(end 0.508 -0.9398)
			(stroke
				(width 0)
				(type default)
			)
			(fill no)
			(layer "F.Fab")
		)
		(pad "1" smd custom
			(at 0 -0.4445 270)
			(size 0.1397 0.1397)
			(layers "F.Cu" "F.Mask" "F.Paste")
			(net "NCSI_10G_TXD0_R")
			(options
				(clearance outline)
				(anchor circle)
			)
			(primitives
				(gr_poly
					(pts
						(arc
							(start -0.1778 -0.2794)
							(mid -0.249642 -0.249642)
							(end -0.2794 -0.1778)
						)
						(arc
							(start -0.2794 0.1778)
							(mid -0.249642 0.249642)
							(end -0.1778 0.2794)
						)
						(arc
							(start 0.1778 0.2794)
							(mid 0.249642 0.249642)
							(end 0.2794 0.1778)
						)
						(arc
							(start 0.2794 -0.1778)
							(mid 0.249642 -0.249642)
							(end 0.1778 -0.2794)
						)
					)
					(width 0)
					(fill yes)
				)
			)
		)
		(pad "2" smd custom
			(at 0 0.4445 270)
			(size 0.1397 0.1397)
			(layers "F.Cu" "F.Mask" "F.Paste")
			(net "NCSI_10G_TXD0")
			(options
				(clearance outline)
				(anchor circle)
			)
			(primitives
				(gr_poly
					(pts
						(arc
							(start -0.1778 -0.2794)
							(mid -0.249642 -0.249642)
							(end -0.2794 -0.1778)
						)
						(arc
							(start -0.2794 0.1778)
							(mid -0.249642 0.249642)
							(end -0.1778 0.2794)
						)
						(arc
							(start 0.1778 0.2794)
							(mid 0.249642 0.249642)
							(end 0.2794 0.1778)
						)
						(arc
							(start 0.2794 -0.1778)
							(mid 0.249642 -0.249642)
							(end 0.1778 -0.2794)
						)
					)
					(width 0)
					(fill yes)
				)
			)
		)
	)
	(footprint ""
		(layer "F.Cu")
		(at 333.366872 -229.307136 -90)
		(property "Reference" "TP84"
			(at 0 0 270)
			(layer "F.SilkS")
			(hide yes)
			(effects
				(font
					(size 1.27 1.27)
				)
			)
		)
		(property "Value" "TPAD32-GP"
			(at 0 -3.166364 270)
			(unlocked yes)
			(layer "F.Fab")
			(hide yes)
			(effects
				(font
					(size 1.016 1.016)
					(thickness 0.1524)
				)
			)
		)
		(property "Device Type" "TPAD32"
			(at 0 -4.690618 270)
			(unlocked yes)
			(layer "F.Fab")
			(hide yes)
			(effects
				(font
					(size 1.016 1.016)
					(thickness 0.1524)
				)
			)
		)
		(duplicate_pad_numbers_are_jumpers no)
		(fp_poly
			(pts
				(arc
					(start 0 -0.4064)
					(mid 0 0.4064)
					(end 0 -0.4064)
				)
			)
			(stroke
				(width 0)
				(type default)
			)
			(fill no)
			(layer "F.CrtYd")
		)
		(fp_poly
			(pts
				(arc
					(start 0 -0.7112)
					(mid 0 0.7112)
					(end 0 -0.7112)
				)
			)
			(stroke
				(width 0)
				(type default)
			)
			(fill no)
			(layer "F.Fab")
		)
		(pad "1" smd circle
			(at 0 0 270)
			(size 0.8128 0.8128)
			(layers "F.Cu" "F.Mask" "F.Paste")
			(net "VOL_SEN_ALERT")
		)
	)
	(footprint ""
		(layer "F.Cu")
		(at 184.776872 -204.796136 -90)
		(property "Reference" "R152"
			(at 0 0 270)
			(layer "F.SilkS")
			(hide yes)
			(effects
				(font
					(size 1.27 1.27)
				)
			)
		)
		(property "Value" "0R2J-2-GP"
			(at 0.064008 -3.993896 270)
			(unlocked yes)
			(layer "F.Fab")
			(hide yes)
			(effects
				(font
					(size 1.016 1.016)
					(thickness 0.1524)
				)
			)
		)
		(property "Device Type" "R402H16"
			(at 0.064008 -5.517896 270)
			(unlocked yes)
			(layer "F.Fab")
			(hide yes)
			(effects
				(font
					(size 1.016 1.016)
					(thickness 0.1524)
				)
			)
		)
		(duplicate_pad_numbers_are_jumpers no)
		(fp_line
			(start -0.508 -0.9398)
			(end -0.508 0.9398)
			(stroke
				(width 0.1524)
				(type default)
			)
			(layer "F.SilkS")
		)
		(fp_line
			(start 0.508 -0.9398)
			(end -0.508 -0.9398)
			(stroke
				(width 0.1524)
				(type default)
			)
			(layer "F.SilkS")
		)
		(fp_rect
			(start -0.508 0.9398)
			(end 0.508 -0.9398)
			(stroke
				(width 0)
				(type default)
			)
			(fill no)
			(layer "F.CrtYd")
		)
		(fp_rect
			(start -0.508 0.9398)
			(end 0.508 -0.9398)
			(stroke
				(width 0)
				(type default)
			)
			(fill no)
			(layer "F.Fab")
		)
		(pad "1" smd custom
			(at 0 -0.4445 270)
			(size 0.1397 0.1397)
			(layers "F.Cu" "F.Mask" "F.Paste")
			(net "SAS_I2C_B_BUF_SDA_R")
			(options
				(clearance outline)
				(anchor circle)
			)
			(primitives
				(gr_poly
					(pts
						(arc
							(start -0.1778 -0.2794)
							(mid -0.249642 -0.249642)
							(end -0.2794 -0.1778)
						)
						(arc
							(start -0.2794 0.1778)
							(mid -0.249642 0.249642)
							(end -0.1778 0.2794)
						)
						(arc
							(start 0.1778 0.2794)
							(mid 0.249642 0.249642)
							(end 0.2794 0.1778)
						)
						(arc
							(start 0.2794 -0.1778)
							(mid 0.249642 -0.249642)
							(end 0.1778 -0.2794)
						)
					)
					(width 0)
					(fill yes)
				)
			)
		)
		(pad "2" smd custom
			(at 0 0.4445 270)
			(size 0.1397 0.1397)
			(layers "F.Cu" "F.Mask" "F.Paste")
			(net "SAS_I2C_B_BUF_SDA")
			(options
				(clearance outline)
				(anchor circle)
			)
			(primitives
				(gr_poly
					(pts
						(arc
							(start -0.1778 -0.2794)
							(mid -0.249642 -0.249642)
							(end -0.2794 -0.1778)
						)
						(arc
							(start -0.2794 0.1778)
							(mid -0.249642 0.249642)
							(end -0.1778 0.2794)
						)
						(arc
							(start 0.1778 0.2794)
							(mid 0.249642 0.249642)
							(end 0.2794 0.1778)
						)
						(arc
							(start 0.2794 -0.1778)
							(mid 0.249642 -0.249642)
							(end 0.1778 -0.2794)
						)
					)
					(width 0)
					(fill yes)
				)
			)
		)
	)
	(footprint ""
		(layer "F.Cu")
		(at 298.45 -157.734 90)
		(property "Reference" "R672"
			(at 0 0 90)
			(layer "F.SilkS")
			(hide yes)
			(effects
				(font
					(size 1.27 1.27)
				)
			)
		)
		(property "Value" "0R2J-2-GP"
			(at 0.064008 -3.993896 90)
			(unlocked yes)
			(layer "F.Fab")
			(hide yes)
			(effects
				(font
					(size 1.016 1.016)
					(thickness 0.1524)
				)
			)
		)
		(property "Device Type" "R402H16"
			(at 0.064008 -5.517896 90)
			(unlocked yes)
			(layer "F.Fab")
			(hide yes)
			(effects
				(font
					(size 1.016 1.016)
					(thickness 0.1524)
				)
			)
		)
		(duplicate_pad_numbers_are_jumpers no)
		(fp_line
			(start 0.508 -0.9398)
			(end -0.508 -0.9398)
			(stroke
				(width 0.1524)
				(type default)
			)
			(layer "F.SilkS")
		)
		(fp_line
			(start -0.508 -0.9398)
			(end -0.508 0.9398)
			(stroke
				(width 0.1524)
				(type default)
			)
			(layer "F.SilkS")
		)
		(fp_rect
			(start -0.508 0.9398)
			(end 0.508 -0.9398)
			(stroke
				(width 0)
				(type default)
			)
			(fill no)
			(layer "F.CrtYd")
		)
		(fp_rect
			(start -0.508 0.9398)
			(end 0.508 -0.9398)
			(stroke
				(width 0)
				(type default)
			)
			(fill no)
			(layer "F.Fab")
		)
		(pad "1" smd custom
			(at 0 -0.4445 90)
			(size 0.1397 0.1397)
			(layers "F.Cu" "F.Mask" "F.Paste")
			(net "CLK_50M_BMC_NCSI")
			(options
				(clearance outline)
				(anchor circle)
			)
			(primitives
				(gr_poly
					(pts
						(arc
							(start -0.1778 -0.2794)
							(mid -0.249642 -0.249642)
							(end -0.2794 -0.1778)
						)
						(arc
							(start -0.2794 0.1778)
							(mid -0.249642 0.249642)
							(end -0.1778 0.2794)
						)
						(arc
							(start 0.1778 0.2794)
							(mid 0.249642 0.249642)
							(end 0.2794 0.1778)
						)
						(arc
							(start 0.2794 -0.1778)
							(mid 0.249642 -0.249642)
							(end 0.1778 -0.2794)
						)
					)
					(width 0)
					(fill yes)
				)
			)
		)
		(pad "2" smd custom
			(at 0 0.4445 90)
			(size 0.1397 0.1397)
			(layers "F.Cu" "F.Mask" "F.Paste")
			(net "CLK_50M_BMC_NCSI_R")
			(options
				(clearance outline)
				(anchor circle)
			)
			(primitives
				(gr_poly
					(pts
						(arc
							(start -0.1778 -0.2794)
							(mid -0.249642 -0.249642)
							(end -0.2794 -0.1778)
						)
						(arc
							(start -0.2794 0.1778)
							(mid -0.249642 0.249642)
							(end -0.1778 0.2794)
						)
						(arc
							(start 0.1778 0.2794)
							(mid 0.249642 0.249642)
							(end 0.2794 0.1778)
						)
						(arc
							(start 0.2794 -0.1778)
							(mid 0.249642 -0.249642)
							(end 0.1778 -0.2794)
						)
					)
					(width 0)
					(fill yes)
				)
			)
		)
	)
	(footprint ""
		(layer "F.Cu")
		(at 152.247092 -114.583464 -90)
		(property "Reference" "SR835"
			(at 0 0 270)
			(layer "F.SilkS")
			(hide yes)
			(effects
				(font
					(size 1.27 1.27)
				)
			)
		)
		(property "Value" "D51R3F-2-GP"
			(at -0.0254 -2.5146 270)
			(unlocked yes)
			(layer "F.Fab")
			(hide yes)
			(effects
				(font
					(size 1.016 1.016)
					(thickness 0.1524)
				)
			)
		)
		(property "Device Type" "R603H22"
			(at -0.0254 -4.0386 270)
			(unlocked yes)
			(layer "F.Fab")
			(hide yes)
			(effects
				(font
					(size 1.016 1.016)
					(thickness 0.1524)
				)
			)
		)
		(duplicate_pad_numbers_are_jumpers no)
		(fp_line
			(start -0.4826 0)
			(end -0.2032 0)
			(stroke
				(width 0.2032)
				(type default)
			)
			(layer "F.SilkS")
		)
		(fp_line
			(start 0.2032 0)
			(end 0.4826 0)
			(stroke
				(width 0.2032)
				(type default)
			)
			(layer "F.SilkS")
		)
		(fp_rect
			(start -0.5842 1.3335)
			(end 0.5842 -1.3335)
			(stroke
				(width 0)
				(type default)
			)
			(fill no)
			(layer "F.CrtYd")
		)
		(fp_rect
			(start -0.5842 1.3335)
			(end 0.5842 -1.3335)
			(stroke
				(width 0)
				(type default)
			)
			(fill no)
			(layer "F.Fab")
		)
		(pad "1" smd custom
			(at 0 -0.762 270)
			(size 0.2159 0.2159)
			(layers "F.Cu" "F.Mask" "F.Paste")
			(net "P0V9_E")
			(options
				(clearance outline)
				(anchor circle)
			)
			(primitives
				(gr_poly
					(pts
						(arc
							(start -0.3302 -0.4318)
							(mid -0.402042 -0.402042)
							(end -0.4318 -0.3302)
						)
						(arc
							(start -0.4318 0.3302)
							(mid -0.402042 0.402042)
							(end -0.3302 0.4318)
						)
						(arc
							(start 0.3302 0.4318)
							(mid 0.402042 0.402042)
							(end 0.4318 0.3302)
						)
						(arc
							(start 0.4318 -0.3302)
							(mid 0.402042 -0.402042)
							(end 0.3302 -0.4318)
						)
					)
					(width 0)
					(fill yes)
				)
			)
		)
		(pad "2" smd custom
			(at 0 0.762 270)
			(size 0.2159 0.2159)
			(layers "F.Cu" "F.Mask" "F.Paste")
			(net "GB_VDDA")
			(options
				(clearance outline)
				(anchor circle)
			)
			(primitives
				(gr_poly
					(pts
						(arc
							(start -0.3302 -0.4318)
							(mid -0.402042 -0.402042)
							(end -0.4318 -0.3302)
						)
						(arc
							(start -0.4318 0.3302)
							(mid -0.402042 0.402042)
							(end -0.3302 0.4318)
						)
						(arc
							(start 0.3302 0.4318)
							(mid 0.402042 0.402042)
							(end 0.4318 0.3302)
						)
						(arc
							(start 0.4318 -0.3302)
							(mid 0.402042 -0.402042)
							(end 0.3302 -0.4318)
						)
					)
					(width 0)
					(fill yes)
				)
			)
		)
	)
	(footprint ""
		(layer "F.Cu")
		(at 104.02697 -76.454)
		(property "Reference" "SR861"
			(at 0 0 0)
			(layer "F.SilkS")
			(hide yes)
			(effects
				(font
					(size 1.27 1.27)
				)
			)
		)
		(property "Value" "0R2J-2-GP"
			(at 0.064008 -3.993896 0)
			(unlocked yes)
			(layer "F.Fab")
			(hide yes)
			(effects
				(font
					(size 1.016 1.016)
					(thickness 0.1524)
				)
			)
		)
		(property "Device Type" "R402H16"
			(at 0.064008 -5.517896 0)
			(unlocked yes)
			(layer "F.Fab")
			(hide yes)
			(effects
				(font
					(size 1.016 1.016)
					(thickness 0.1524)
				)
			)
		)
		(duplicate_pad_numbers_are_jumpers no)
		(fp_line
			(start -0.508 -0.9398)
			(end -0.508 0.9398)
			(stroke
				(width 0.1524)
				(type default)
			)
			(layer "F.SilkS")
		)
		(fp_line
			(start 0.508 -0.9398)
			(end -0.508 -0.9398)
			(stroke
				(width 0.1524)
				(type default)
			)
			(layer "F.SilkS")
		)
		(fp_rect
			(start -0.508 0.9398)
			(end 0.508 -0.9398)
			(stroke
				(width 0)
				(type default)
			)
			(fill no)
			(layer "F.CrtYd")
		)
		(fp_rect
			(start -0.508 0.9398)
			(end 0.508 -0.9398)
			(stroke
				(width 0)
				(type default)
			)
			(fill no)
			(layer "F.Fab")
		)
		(pad "1" smd custom
			(at 0 -0.4445)
			(size 0.1397 0.1397)
			(layers "F.Cu" "F.Mask" "F.Paste")
			(net "JTAG_EXP_TMS")
			(options
				(clearance outline)
				(anchor circle)
			)
			(primitives
				(gr_poly
					(pts
						(arc
							(start -0.1778 -0.2794)
							(mid -0.249642 -0.249642)
							(end -0.2794 -0.1778)
						)
						(arc
							(start -0.2794 0.1778)
							(mid -0.249642 0.249642)
							(end -0.1778 0.2794)
						)
						(arc
							(start 0.1778 0.2794)
							(mid 0.249642 0.249642)
							(end 0.2794 0.1778)
						)
						(arc
							(start 0.2794 -0.1778)
							(mid 0.249642 -0.249642)
							(end 0.1778 -0.2794)
						)
					)
					(width 0)
					(fill yes)
				)
			)
		)
		(pad "2" smd custom
			(at 0 0.4445)
			(size 0.1397 0.1397)
			(layers "F.Cu" "F.Mask" "F.Paste")
			(net "JTAG_EXP_IOC_TMS")
			(options
				(clearance outline)
				(anchor circle)
			)
			(primitives
				(gr_poly
					(pts
						(arc
							(start -0.1778 -0.2794)
							(mid -0.249642 -0.249642)
							(end -0.2794 -0.1778)
						)
						(arc
							(start -0.2794 0.1778)
							(mid -0.249642 0.249642)
							(end -0.1778 0.2794)
						)
						(arc
							(start 0.1778 0.2794)
							(mid 0.249642 0.249642)
							(end 0.2794 0.1778)
						)
						(arc
							(start 0.2794 -0.1778)
							(mid 0.249642 -0.249642)
							(end 0.1778 -0.2794)
						)
					)
					(width 0)
					(fill yes)
				)
			)
		)
	)
	(footprint ""
		(layer "F.Cu")
		(at 19.381216 -224.97288 -90)
		(property "Reference" "R636"
			(at 0 0 270)
			(layer "F.SilkS")
			(hide yes)
			(effects
				(font
					(size 1.27 1.27)
				)
			)
		)
		(property "Value" "4K7R2F-GP"
			(at 0.064008 -3.993896 270)
			(unlocked yes)
			(layer "F.Fab")
			(hide yes)
			(effects
				(font
					(size 1.016 1.016)
					(thickness 0.1524)
				)
			)
		)
		(property "Device Type" "R402H16"
			(at 0.064008 -5.517896 270)
			(unlocked yes)
			(layer "F.Fab")
			(hide yes)
			(effects
				(font
					(size 1.016 1.016)
					(thickness 0.1524)
				)
			)
		)
		(duplicate_pad_numbers_are_jumpers no)
		(fp_line
			(start -0.508 -0.9398)
			(end -0.508 0.9398)
			(stroke
				(width 0.1524)
				(type default)
			)
			(layer "F.SilkS")
		)
		(fp_line
			(start 0.508 -0.9398)
			(end -0.508 -0.9398)
			(stroke
				(width 0.1524)
				(type default)
			)
			(layer "F.SilkS")
		)
		(fp_rect
			(start -0.508 0.9398)
			(end 0.508 -0.9398)
			(stroke
				(width 0)
				(type default)
			)
			(fill no)
			(layer "F.CrtYd")
		)
		(fp_rect
			(start -0.508 0.9398)
			(end 0.508 -0.9398)
			(stroke
				(width 0)
				(type default)
			)
			(fill no)
			(layer "F.Fab")
		)
		(pad "1" smd custom
			(at 0 -0.4445 270)
			(size 0.1397 0.1397)
			(layers "F.Cu" "F.Mask" "F.Paste")
			(net "P3V3_STBY")
			(options
				(clearance outline)
				(anchor circle)
			)
			(primitives
				(gr_poly
					(pts
						(arc
							(start -0.1778 -0.2794)
							(mid -0.249642 -0.249642)
							(end -0.2794 -0.1778)
						)
						(arc
							(start -0.2794 0.1778)
							(mid -0.249642 0.249642)
							(end -0.1778 0.2794)
						)
						(arc
							(start 0.1778 0.2794)
							(mid 0.249642 0.249642)
							(end 0.2794 0.1778)
						)
						(arc
							(start 0.2794 -0.1778)
							(mid 0.249642 -0.249642)
							(end 0.1778 -0.2794)
						)
					)
					(width 0)
					(fill yes)
				)
			)
		)
		(pad "2" smd custom
			(at 0 0.4445 270)
			(size 0.1397 0.1397)
			(layers "F.Cu" "F.Mask" "F.Paste")
			(net "IO_EXP_HDD_PWR_A3")
			(options
				(clearance outline)
				(anchor circle)
			)
			(primitives
				(gr_poly
					(pts
						(arc
							(start -0.1778 -0.2794)
							(mid -0.249642 -0.249642)
							(end -0.2794 -0.1778)
						)
						(arc
							(start -0.2794 0.1778)
							(mid -0.249642 0.249642)
							(end -0.1778 0.2794)
						)
						(arc
							(start 0.1778 0.2794)
							(mid 0.249642 0.249642)
							(end 0.2794 0.1778)
						)
						(arc
							(start 0.2794 -0.1778)
							(mid 0.249642 -0.249642)
							(end 0.1778 -0.2794)
						)
					)
					(width 0)
					(fill yes)
				)
			)
		)
	)
	(footprint ""
		(layer "F.Cu")
		(at 210.947 -103.886 180)
		(property "Reference" "PR123"
			(at 0 0 180)
			(layer "F.SilkS")
			(hide yes)
			(effects
				(font
					(size 1.27 1.27)
				)
			)
		)
		(property "Value" "4K75R2F-1-GP"
			(at 0.064008 -3.993896 180)
			(unlocked yes)
			(layer "F.Fab")
			(hide yes)
			(effects
				(font
					(size 1.016 1.016)
					(thickness 0.1524)
				)
			)
		)
		(property "Device Type" "R402H16"
			(at 0.064008 -5.517896 180)
			(unlocked yes)
			(layer "F.Fab")
			(hide yes)
			(effects
				(font
					(size 1.016 1.016)
					(thickness 0.1524)
				)
			)
		)
		(duplicate_pad_numbers_are_jumpers no)
		(fp_line
			(start 0.508 -0.9398)
			(end -0.508 -0.9398)
			(stroke
				(width 0.1524)
				(type default)
			)
			(layer "F.SilkS")
		)
		(fp_line
			(start -0.508 -0.9398)
			(end -0.508 0.9398)
			(stroke
				(width 0.1524)
				(type default)
			)
			(layer "F.SilkS")
		)
		(fp_rect
			(start -0.508 0.9398)
			(end 0.508 -0.9398)
			(stroke
				(width 0)
				(type default)
			)
			(fill no)
			(layer "F.CrtYd")
		)
		(fp_rect
			(start -0.508 0.9398)
			(end 0.508 -0.9398)
			(stroke
				(width 0)
				(type default)
			)
			(fill no)
			(layer "F.Fab")
		)
		(pad "1" smd custom
			(at 0 -0.4445 180)
			(size 0.1397 0.1397)
			(layers "F.Cu" "F.Mask" "F.Paste")
			(net "TPS74801_1V5_C_FB")
			(options
				(clearance outline)
				(anchor circle)
			)
			(primitives
				(gr_poly
					(pts
						(arc
							(start -0.1778 -0.2794)
							(mid -0.249642 -0.249642)
							(end -0.2794 -0.1778)
						)
						(arc
							(start -0.2794 0.1778)
							(mid -0.249642 0.249642)
							(end -0.1778 0.2794)
						)
						(arc
							(start 0.1778 0.2794)
							(mid 0.249642 0.249642)
							(end 0.2794 0.1778)
						)
						(arc
							(start 0.2794 -0.1778)
							(mid 0.249642 -0.249642)
							(end 0.1778 -0.2794)
						)
					)
					(width 0)
					(fill yes)
				)
			)
		)
		(pad "2" smd custom
			(at 0 0.4445 180)
			(size 0.1397 0.1397)
			(layers "F.Cu" "F.Mask" "F.Paste")
			(net "GND")
			(options
				(clearance outline)
				(anchor circle)
			)
			(primitives
				(gr_poly
					(pts
						(arc
							(start -0.1778 -0.2794)
							(mid -0.249642 -0.249642)
							(end -0.2794 -0.1778)
						)
						(arc
							(start -0.2794 0.1778)
							(mid -0.249642 0.249642)
							(end -0.1778 0.2794)
						)
						(arc
							(start 0.1778 0.2794)
							(mid 0.249642 0.249642)
							(end 0.2794 0.1778)
						)
						(arc
							(start 0.2794 -0.1778)
							(mid 0.249642 -0.249642)
							(end 0.1778 -0.2794)
						)
					)
					(width 0)
					(fill yes)
				)
			)
		)
	)
)
